# BASEBOARD_FAB2 (Tioga Pass) — schematic netlist excerpt (pin names and nets, part order shuffled) for the footprints in the layout excerpt that follows; sources: Cadence DE-HDL packaged netlist, KiCad conversion of Wiwynn_Tioga_Pass_MB.brd

R3P46  RES  33.2 1% CHIP  pkg 0402  page 92 : A = FM_CPU1_FIVR_FAULT_R_LVT3 ; B = FM_CPU1_FIVR_FAULT_LVT3
R1W27  RES  0.0 5% CHIP  pkg 0402  page 190 : A = FM_PWR_BTN_N ; B = FM_PWR_BTN_R2_N
R6P37  RES  2.0K 1% EMPTY  pkg 0402  page 201 : A = P3V3_STBY ; B = SMB_VR_STBY_LVC3_SCL

(kicad_pcb
	(version 20260206)
	(generator "pcbnew")
	(generator_version "10.0")
	(general
		(thickness 1.6)
		(legacy_teardrops no)
	)
	(paper "A4")
	(title_block
		(title "Wiwynn_Tioga_Pass_MB.brd")
		(comment 1 "Tioga Pass / footprints 3581-3583 of 4770")
	)
	(layers
		(0 "F.Cu" signal "TOP")
		(4 "In1.Cu" signal "L2GND")
		(6 "In2.Cu" signal "L3")
		(8 "In3.Cu" signal "L4GND")
		(10 "In4.Cu" signal "L5")
		(12 "In5.Cu" signal "L6GND")
		(14 "In6.Cu" signal "L7VCC")
		(16 "In7.Cu" signal "L8VCC")
		(18 "In8.Cu" signal "L9GND")
		(20 "In9.Cu" signal "L10")
		(22 "In10.Cu" signal "L11GND")
		(24 "In11.Cu" signal "L12")
		(26 "In12.Cu" signal "L13GND")
		(2 "B.Cu" signal "BOTTOM")
		(9 "F.Adhes" user "F.Adhesive")
		(11 "B.Adhes" user "B.Adhesive")
		(13 "F.Paste" user "Package Geometry/Pastemask Top")
		(15 "B.Paste" user "Package Geometry/Pastemask Bottom")
		(5 "F.SilkS" user "Ref Des/Silkscreen Top")
		(7 "B.SilkS" user "Ref Des/Silkscreen Bottom")
		(1 "F.Mask" user "Board Geometry/Soldermask Top")
		(3 "B.Mask" user "Board Geometry/Soldermask Bottom")
		(17 "Dwgs.User" user "User.Drawings")
		(19 "Cmts.User" user "User.Comments")
		(21 "Eco1.User" user "User.Eco1")
		(23 "Eco2.User" user "User.Eco2")
		(25 "Edge.Cuts" user "Board Geometry/Outline")
		(27 "Margin" user)
		(31 "F.CrtYd" user "Package Geometry/Place Bound Top")
		(29 "B.CrtYd" user "Package Geometry/Place Bound Bottom")
		(35 "F.Fab" user "Ref Des/Assembly Top")
		(33 "B.Fab" user "Ref Des/Assembly Bottom")
	)
	(footprint ""
		(layer "B.Cu")
		(at 179.206144 -68.341494 -90)
		(property "Reference" "R6P37"
			(at 0 0 90)
			(layer "B.SilkS")
			(hide yes)
			(effects
				(font
					(size 1.27 1.27)
				)
				(justify mirror)
			)
		)
		(property "Value" ""
			(at 0 0 90)
			(layer "B.Fab")
			(effects
				(font
					(size 1.27 1.27)
				)
				(justify mirror)
			)
		)
		(duplicate_pad_numbers_are_jumpers no)
		(fp_rect
			(start -0.2794 -0.1016)
			(end 0.2794 0.9906)
			(stroke
				(width 0)
				(type default)
			)
			(fill no)
			(layer "B.CrtYd")
		)
		(fp_line
			(start -0.2794 0.9906)
			(end -0.2794 -0.1016)
			(stroke
				(width 0.1)
				(type default)
			)
			(layer "B.Fab")
		)
		(fp_line
			(start 0.2794 0.9906)
			(end -0.2794 0.9906)
			(stroke
				(width 0.1)
				(type default)
			)
			(layer "B.Fab")
		)
		(fp_line
			(start -0.2794 -0.1016)
			(end 0.2794 -0.1016)
			(stroke
				(width 0.1)
				(type default)
			)
			(layer "B.Fab")
		)
		(fp_line
			(start 0.2794 -0.1016)
			(end 0.2794 0.9906)
			(stroke
				(width 0.1)
				(type default)
			)
			(layer "B.Fab")
		)
		(pad "1" smd rect
			(at 0 0 90)
			(size 0.508 0.508)
			(layers "B.Cu" "B.Mask" "B.Paste")
			(net "P3V3_STBY")
		)
		(pad "2" smd rect
			(at 0 0.889 90)
			(size 0.508 0.508)
			(layers "B.Cu" "B.Mask" "B.Paste")
			(net "SMB_VR_STBY_LVC3_SCL")
		)
		(zone
			(layer "B.Cu")
			(hatch none 0.5)
			(connect_pads
				(clearance 0)
			)
			(min_thickness 0.25)
			(keepout
				(tracks not_allowed)
				(vias allowed)
				(pads allowed)
				(copperpour not_allowed)
				(footprints allowed)
			)
			(placement
				(enabled no)
				(sheetname "")
			)
			(fill
				(thermal_gap 0.5)
				(thermal_bridge_width 0.5)
				(island_removal_mode 0)
			)
			(polygon
				(pts
					(xy 178.952144 -68.595494) (xy 178.571144 -68.595494) (xy 178.571144 -68.087494) (xy 178.952144 -68.087494)
				)
			)
		)
		(zone
			(layer "B.Cu")
			(hatch none 0.5)
			(connect_pads
				(clearance 0)
			)
			(min_thickness 0.25)
			(keepout
				(tracks allowed)
				(vias not_allowed)
				(pads allowed)
				(copperpour not_allowed)
				(footprints allowed)
			)
			(placement
				(enabled no)
				(sheetname "")
			)
			(fill
				(thermal_gap 0.5)
				(thermal_bridge_width 0.5)
				(island_removal_mode 0)
			)
			(polygon
				(pts
					(xy 178.952144 -68.595494) (xy 178.571144 -68.595494) (xy 178.571144 -68.087494) (xy 178.952144 -68.087494)
				)
			)
		)
	)
	(footprint ""
		(layer "B.Cu")
		(at 366.522 -62.2935 180)
		(property "Reference" "R3P46"
			(at 0 0 0)
			(layer "B.SilkS")
			(hide yes)
			(effects
				(font
					(size 1.27 1.27)
				)
				(justify mirror)
			)
		)
		(property "Value" ""
			(at 0 0 0)
			(layer "B.Fab")
			(effects
				(font
					(size 1.27 1.27)
				)
				(justify mirror)
			)
		)
		(duplicate_pad_numbers_are_jumpers no)
		(fp_poly
			(pts
				(xy 0.2794 -0.1016) (xy -0.2794 -0.1016) (xy -0.2794 0.9906) (xy 0.2794 0.9906)
			)
			(stroke
				(width 0)
				(type default)
			)
			(fill no)
			(layer "B.CrtYd")
		)
		(fp_line
			(start 0.2794 0.9906)
			(end -0.2794 0.9906)
			(stroke
				(width 0.1)
				(type default)
			)
			(layer "B.Fab")
		)
		(fp_line
			(start 0.2794 -0.1016)
			(end 0.2794 0.9906)
			(stroke
				(width 0.1)
				(type default)
			)
			(layer "B.Fab")
		)
		(fp_line
			(start -0.2794 0.9906)
			(end -0.2794 -0.1016)
			(stroke
				(width 0.1)
				(type default)
			)
			(layer "B.Fab")
		)
		(fp_line
			(start -0.2794 -0.1016)
			(end 0.2794 -0.1016)
			(stroke
				(width 0.1)
				(type default)
			)
			(layer "B.Fab")
		)
		(pad "1" smd rect
			(at 0 0)
			(size 0.508 0.508)
			(layers "B.Cu" "B.Mask" "B.Paste")
			(net "FM_CPU1_FIVR_FAULT_R_LVT3")
		)
		(pad "2" smd rect
			(at 0 0.889)
			(size 0.508 0.508)
			(layers "B.Cu" "B.Mask" "B.Paste")
			(net "FM_CPU1_FIVR_FAULT_LVT3")
		)
		(zone
			(layer "B.Cu")
			(hatch none 0.5)
			(connect_pads
				(clearance 0)
			)
			(min_thickness 0.25)
			(keepout
				(tracks not_allowed)
				(vias allowed)
				(pads allowed)
				(copperpour not_allowed)
				(footprints allowed)
			)
			(placement
				(enabled no)
				(sheetname "")
			)
			(fill
				(thermal_gap 0.5)
				(thermal_bridge_width 0.5)
				(island_removal_mode 0)
			)
			(polygon
				(pts
					(xy 366.268 -62.9285) (xy 366.776 -62.9285) (xy 366.776 -62.5475) (xy 366.268 -62.5475)
				)
			)
		)
		(zone
			(layer "B.Cu")
			(hatch none 0.5)
			(connect_pads
				(clearance 0)
			)
			(min_thickness 0.25)
			(keepout
				(tracks allowed)
				(vias not_allowed)
				(pads allowed)
				(copperpour not_allowed)
				(footprints allowed)
			)
			(placement
				(enabled no)
				(sheetname "")
			)
			(fill
				(thermal_gap 0.5)
				(thermal_bridge_width 0.5)
				(island_removal_mode 0)
			)
			(polygon
				(pts
					(xy 366.268 -62.5475) (xy 366.776 -62.5475) (xy 366.776 -62.9285) (xy 366.268 -62.9285)
				)
			)
		)
	)
	(footprint ""
		(layer "B.Cu")
		(at 376.215656 -92.173298)
		(property "Reference" "R1W27"
			(at 0.8382 -0.67818 0)
			(unlocked yes)
			(layer "B.SilkS")
			(effects
				(font
					(size 0.4064 0.254)
					(thickness 0.1524)
				)
				(justify left mirror)
			)
		)
		(property "Value" ""
			(at 0 0 0)
			(layer "B.Fab")
			(effects
				(font
					(size 1.27 1.27)
				)
				(justify mirror)
			)
		)
		(duplicate_pad_numbers_are_jumpers no)
		(fp_poly
			(pts
				(xy 0.2794 -0.1016) (xy -0.2794 -0.1016) (xy -0.2794 0.9906) (xy 0.2794 0.9906)
			)
			(stroke
				(width 0)
				(type default)
			)
			(fill no)
			(layer "B.CrtYd")
		)
		(fp_line
			(start -0.2794 -0.1016)
			(end 0.2794 -0.1016)
			(stroke
				(width 0.1)
				(type default)
			)
			(layer "B.Fab")
		)
		(fp_line
			(start -0.2794 0.9906)
			(end -0.2794 -0.1016)
			(stroke
				(width 0.1)
				(type default)
			)
			(layer "B.Fab")
		)
		(fp_line
			(start 0.2794 -0.1016)
			(end 0.2794 0.9906)
			(stroke
				(width 0.1)
				(type default)
			)
			(layer "B.Fab")
		)
		(fp_line
			(start 0.2794 0.9906)
			(end -0.2794 0.9906)
			(stroke
				(width 0.1)
				(type default)
			)
			(layer "B.Fab")
		)
		(pad "1" smd rect
			(at 0 0 180)
			(size 0.508 0.508)
			(layers "B.Cu" "B.Mask" "B.Paste")
			(net "FM_PWR_BTN_N")
		)
		(pad "2" smd rect
			(at 0 0.889 180)
			(size 0.508 0.508)
			(layers "B.Cu" "B.Mask" "B.Paste")
			(net "FM_PWR_BTN_R2_N")
		)
		(zone
			(layer "B.Cu")
			(hatch none 0.5)
			(connect_pads
				(clearance 0)
			)
			(min_thickness 0.25)
			(keepout
				(tracks allowed)
				(vias not_allowed)
				(pads allowed)
				(copperpour not_allowed)
				(footprints allowed)
			)
			(placement
				(enabled no)
				(sheetname "")
			)
			(fill
				(thermal_gap 0.5)
				(thermal_bridge_width 0.5)
				(island_removal_mode 0)
			)
			(polygon
				(pts
					(xy 376.469656 -91.919298) (xy 375.961656 -91.919298) (xy 375.961656 -91.538298) (xy 376.469656 -91.538298)
				)
			)
		)
		(zone
			(layer "B.Cu")
			(hatch none 0.5)
			(connect_pads
				(clearance 0)
			)
			(min_thickness 0.25)
			(keepout
				(tracks not_allowed)
				(vias allowed)
				(pads allowed)
				(copperpour not_allowed)
				(footprints allowed)
			)
			(placement
				(enabled no)
				(sheetname "")
			)
			(fill
				(thermal_gap 0.5)
				(thermal_bridge_width 0.5)
				(island_removal_mode 0)
			)
			(polygon
				(pts
					(xy 376.469656 -91.538298) (xy 375.961656 -91.538298) (xy 375.961656 -91.919298) (xy 376.469656 -91.919298)
				)
			)
		)
	)
)
